(kicad_pcb
	(version 20260206)
	(generator "pcbnew")
	(generator_version "10.0")
	(general
		(thickness 1.6)
		(legacy_teardrops no)
	)
	(paper "A4")
	(title_block
		(title "04192023_DAF0TMB3IC0_F0TG_MB_C_brd_V02_OCP.brd")
		(comment 1 "Grand Teton / footprints 3859-3864 of 8354")
	)
	(layers
		(0 "F.Cu" signal "TOP")
		(4 "In1.Cu" signal "GND")
		(6 "In2.Cu" signal "IN1")
		(8 "In3.Cu" signal "GND1")
		(10 "In4.Cu" signal "IN2")
		(12 "In5.Cu" signal "GND2")
		(14 "In6.Cu" signal "IN3")
		(16 "In7.Cu" signal "GND3")
		(18 "In8.Cu" signal "VCC")
		(20 "In9.Cu" signal "VCC1")
		(22 "In10.Cu" signal "GND4")
		(24 "In11.Cu" signal "IN4")
		(26 "In12.Cu" signal "GND5")
		(28 "In13.Cu" signal "IN5")
		(30 "In14.Cu" signal "GND6")
		(32 "In15.Cu" signal "IN6")
		(34 "In16.Cu" signal "GND7")
		(2 "B.Cu" signal "BOTTOM")
		(9 "F.Adhes" user "F.Adhesive")
		(11 "B.Adhes" user "B.Adhesive")
		(13 "F.Paste" user "Package Geometry/Pastemask Top")
		(15 "B.Paste" user "Package Geometry/Pastemask Bottom")
		(5 "F.SilkS" user "Ref Des/Silkscreen Top")
		(7 "B.SilkS" user "Ref Des/Silkscreen Bottom")
		(1 "F.Mask" user "Board Geometry/Soldermask Top")
		(3 "B.Mask" user "Board Geometry/Soldermask Bottom")
		(17 "Dwgs.User" user "User.Drawings")
		(19 "Cmts.User" user "User.Comments")
		(21 "Eco1.User" user "User.Eco1")
		(23 "Eco2.User" user "User.Eco2")
		(25 "Edge.Cuts" user "Board Geometry/Outline")
		(27 "Margin" user)
		(31 "F.CrtYd" user "Package Geometry/Place Bound Top")
		(29 "B.CrtYd" user "Package Geometry/Place Bound Bottom")
		(35 "F.Fab" user "Ref Des/Assembly Top")
		(33 "B.Fab" user "Ref Des/Assembly Bottom")
	)
	(footprint ""
		(layer "F.Cu")
		(at 128.906778 -47.121064)
		(property "Reference" "R6204"
			(at 0 0 0)
			(layer "F.SilkS")
			(hide yes)
			(effects
				(font
					(size 1.27 1.27)
				)
			)
		)
		(property "Value" ""
			(at 0 0 0)
			(layer "F.Fab")
			(effects
				(font
					(size 1.27 1.27)
				)
			)
		)
		(duplicate_pad_numbers_are_jumpers no)
		(fp_line
			(start -0.7874 -0.4064)
			(end 0.7874 -0.4064)
			(stroke
				(width 0.1524)
				(type default)
			)
			(layer "F.SilkS")
		)
		(fp_line
			(start -0.7874 0.4064)
			(end -0.7874 -0.4064)
			(stroke
				(width 0.1524)
				(type default)
			)
			(layer "F.SilkS")
		)
		(fp_line
			(start 0.7874 -0.4064)
			(end 0.7874 0.4064)
			(stroke
				(width 0.1524)
				(type default)
			)
			(layer "F.SilkS")
		)
		(fp_line
			(start 0.7874 0.4064)
			(end -0.7874 0.4064)
			(stroke
				(width 0.1524)
				(type default)
			)
			(layer "F.SilkS")
		)
		(fp_line
			(start -0.67945 -0.305054)
			(end -0.12065 -0.305054)
			(stroke
				(width 0.1)
				(type default)
			)
			(layer "F.Fab")
		)
		(fp_line
			(start -0.67945 0.3048)
			(end -0.67945 -0.305054)
			(stroke
				(width 0.1)
				(type default)
			)
			(layer "F.Fab")
		)
		(fp_line
			(start -0.12065 -0.305054)
			(end -0.12065 -0.2794)
			(stroke
				(width 0.1)
				(type default)
			)
			(layer "F.Fab")
		)
		(fp_line
			(start -0.12065 -0.2794)
			(end 0.12065 -0.2794)
			(stroke
				(width 0.1)
				(type default)
			)
			(layer "F.Fab")
		)
		(fp_line
			(start -0.12065 0.2794)
			(end -0.12065 0.3048)
			(stroke
				(width 0.1)
				(type default)
			)
			(layer "F.Fab")
		)
		(fp_line
			(start -0.12065 0.3048)
			(end -0.67945 0.3048)
			(stroke
				(width 0.1)
				(type default)
			)
			(layer "F.Fab")
		)
		(fp_line
			(start 0.120396 0.2794)
			(end -0.12065 0.2794)
			(stroke
				(width 0.1)
				(type default)
			)
			(layer "F.Fab")
		)
		(fp_line
			(start 0.120396 0.3048)
			(end 0.120396 0.2794)
			(stroke
				(width 0.1)
				(type default)
			)
			(layer "F.Fab")
		)
		(fp_line
			(start 0.12065 -0.3048)
			(end 0.67945 -0.3048)
			(stroke
				(width 0.1)
				(type default)
			)
			(layer "F.Fab")
		)
		(fp_line
			(start 0.12065 -0.2794)
			(end 0.12065 -0.3048)
			(stroke
				(width 0.1)
				(type default)
			)
			(layer "F.Fab")
		)
		(fp_line
			(start 0.67945 -0.3048)
			(end 0.67945 0.3048)
			(stroke
				(width 0.1)
				(type default)
			)
			(layer "F.Fab")
		)
		(fp_line
			(start 0.67945 0.3048)
			(end 0.120396 0.3048)
			(stroke
				(width 0.1)
				(type default)
			)
			(layer "F.Fab")
		)
		(pad "1" smd circle
			(at -0.40005 0)
			(size 0 0)
			(layers "F.Cu" "F.Mask" "F.Paste")
			(net "P3V3_AUX")
		)
		(pad "2" smd circle
			(at 0.40005 0)
			(size 0 0)
			(layers "F.Cu" "F.Mask" "F.Paste")
			(net "PU_CPU0_USB_HUB_PWR_EN")
		)
	)
	(footprint ""
		(layer "F.Cu")
		(at 203.454 -337.82)
		(property "Reference" "PR8000"
			(at 0 0 0)
			(layer "F.SilkS")
			(hide yes)
			(effects
				(font
					(size 1.27 1.27)
				)
			)
		)
		(property "Value" ""
			(at 0 0 0)
			(layer "F.Fab")
			(effects
				(font
					(size 1.27 1.27)
				)
			)
		)
		(duplicate_pad_numbers_are_jumpers no)
		(fp_line
			(start -0.7874 -0.4064)
			(end 0.7874 -0.4064)
			(stroke
				(width 0.1524)
				(type default)
			)
			(layer "F.SilkS")
		)
		(fp_line
			(start -0.7874 0.4064)
			(end -0.7874 -0.4064)
			(stroke
				(width 0.1524)
				(type default)
			)
			(layer "F.SilkS")
		)
		(fp_line
			(start 0.7874 -0.4064)
			(end 0.7874 0.4064)
			(stroke
				(width 0.1524)
				(type default)
			)
			(layer "F.SilkS")
		)
		(fp_line
			(start 0.7874 0.4064)
			(end -0.7874 0.4064)
			(stroke
				(width 0.1524)
				(type default)
			)
			(layer "F.SilkS")
		)
		(fp_line
			(start -0.67945 -0.305054)
			(end -0.12065 -0.305054)
			(stroke
				(width 0.1)
				(type default)
			)
			(layer "F.Fab")
		)
		(fp_line
			(start -0.67945 0.3048)
			(end -0.67945 -0.305054)
			(stroke
				(width 0.1)
				(type default)
			)
			(layer "F.Fab")
		)
		(fp_line
			(start -0.12065 -0.305054)
			(end -0.12065 -0.2794)
			(stroke
				(width 0.1)
				(type default)
			)
			(layer "F.Fab")
		)
		(fp_line
			(start -0.12065 -0.2794)
			(end 0.12065 -0.2794)
			(stroke
				(width 0.1)
				(type default)
			)
			(layer "F.Fab")
		)
		(fp_line
			(start -0.12065 0.2794)
			(end -0.12065 0.3048)
			(stroke
				(width 0.1)
				(type default)
			)
			(layer "F.Fab")
		)
		(fp_line
			(start -0.12065 0.3048)
			(end -0.67945 0.3048)
			(stroke
				(width 0.1)
				(type default)
			)
			(layer "F.Fab")
		)
		(fp_line
			(start 0.120396 0.2794)
			(end -0.12065 0.2794)
			(stroke
				(width 0.1)
				(type default)
			)
			(layer "F.Fab")
		)
		(fp_line
			(start 0.120396 0.3048)
			(end 0.120396 0.2794)
			(stroke
				(width 0.1)
				(type default)
			)
			(layer "F.Fab")
		)
		(fp_line
			(start 0.12065 -0.3048)
			(end 0.67945 -0.3048)
			(stroke
				(width 0.1)
				(type default)
			)
			(layer "F.Fab")
		)
		(fp_line
			(start 0.12065 -0.2794)
			(end 0.12065 -0.3048)
			(stroke
				(width 0.1)
				(type default)
			)
			(layer "F.Fab")
		)
		(fp_line
			(start 0.67945 -0.3048)
			(end 0.67945 0.3048)
			(stroke
				(width 0.1)
				(type default)
			)
			(layer "F.Fab")
		)
		(fp_line
			(start 0.67945 0.3048)
			(end 0.120396 0.3048)
			(stroke
				(width 0.1)
				(type default)
			)
			(layer "F.Fab")
		)
		(pad "1" smd circle
			(at -0.40005 0)
			(size 0 0)
			(layers "F.Cu" "F.Mask" "F.Paste")
			(net "SW_PVDD_33_S5_BST")
		)
		(pad "2" smd circle
			(at 0.40005 0)
			(size 0 0)
			(layers "F.Cu" "F.Mask" "F.Paste")
			(net "SW_PVDD_33_S5_BST_R")
		)
	)
	(footprint ""
		(layer "F.Cu")
		(at 347.983048 -342.599772 90)
		(property "Reference" "PC112"
			(at 0 0 90)
			(layer "F.SilkS")
			(hide yes)
			(effects
				(font
					(size 1.27 1.27)
				)
			)
		)
		(property "Value" ""
			(at 0 0 90)
			(layer "F.Fab")
			(effects
				(font
					(size 1.27 1.27)
				)
			)
		)
		(duplicate_pad_numbers_are_jumpers no)
		(fp_line
			(start 0.7874 -0.4064)
			(end 0.7874 0.4064)
			(stroke
				(width 0.1524)
				(type default)
			)
			(layer "F.SilkS")
		)
		(fp_line
			(start -0.7874 -0.4064)
			(end 0.7874 -0.4064)
			(stroke
				(width 0.1524)
				(type default)
			)
			(layer "F.SilkS")
		)
		(fp_line
			(start 0.7874 0.4064)
			(end 0.376428 0.4064)
			(stroke
				(width 0.1524)
				(type default)
			)
			(layer "F.SilkS")
		)
		(fp_line
			(start -0.182372 0.4064)
			(end -0.7874 0.4064)
			(stroke
				(width 0.1524)
				(type default)
			)
			(layer "F.SilkS")
		)
		(fp_line
			(start -0.7874 0.4064)
			(end -0.7874 -0.4064)
			(stroke
				(width 0.1524)
				(type default)
			)
			(layer "F.SilkS")
		)
		(fp_line
			(start -0.12065 -0.305054)
			(end -0.12065 -0.2794)
			(stroke
				(width 0.1)
				(type default)
			)
			(layer "F.Fab")
		)
		(fp_line
			(start -0.67945 -0.305054)
			(end -0.12065 -0.305054)
			(stroke
				(width 0.1)
				(type default)
			)
			(layer "F.Fab")
		)
		(fp_line
			(start 0.67945 -0.3048)
			(end 0.67945 0.3048)
			(stroke
				(width 0.1)
				(type default)
			)
			(layer "F.Fab")
		)
		(fp_line
			(start 0.12065 -0.3048)
			(end 0.67945 -0.3048)
			(stroke
				(width 0.1)
				(type default)
			)
			(layer "F.Fab")
		)
		(fp_line
			(start 0.12065 -0.2794)
			(end 0.12065 -0.3048)
			(stroke
				(width 0.1)
				(type default)
			)
			(layer "F.Fab")
		)
		(fp_line
			(start -0.12065 -0.2794)
			(end 0.12065 -0.2794)
			(stroke
				(width 0.1)
				(type default)
			)
			(layer "F.Fab")
		)
		(fp_line
			(start 0.120396 0.2794)
			(end -0.12065 0.2794)
			(stroke
				(width 0.1)
				(type default)
			)
			(layer "F.Fab")
		)
		(fp_line
			(start -0.12065 0.2794)
			(end -0.12065 0.3048)
			(stroke
				(width 0.1)
				(type default)
			)
			(layer "F.Fab")
		)
		(fp_line
			(start 0.67945 0.3048)
			(end 0.120396 0.3048)
			(stroke
				(width 0.1)
				(type default)
			)
			(layer "F.Fab")
		)
		(fp_line
			(start 0.120396 0.3048)
			(end 0.120396 0.2794)
			(stroke
				(width 0.1)
				(type default)
			)
			(layer "F.Fab")
		)
		(fp_line
			(start -0.12065 0.3048)
			(end -0.67945 0.3048)
			(stroke
				(width 0.1)
				(type default)
			)
			(layer "F.Fab")
		)
		(fp_line
			(start -0.67945 0.3048)
			(end -0.67945 -0.305054)
			(stroke
				(width 0.1)
				(type default)
			)
			(layer "F.Fab")
		)
		(pad "1" smd circle
			(at -0.40005 0 90)
			(size 0 0)
			(layers "F.Cu" "F.Mask" "F.Paste")
			(net "PVDDCR_CPU1_P0_VCC6")
		)
		(pad "2" smd circle
			(at 0.40005 0 90)
			(size 0 0)
			(layers "F.Cu" "F.Mask" "F.Paste")
			(net "GND")
		)
	)
	(footprint ""
		(layer "F.Cu")
		(at 297.486324 -115.148614 180)
		(property "Reference" "R67"
			(at 0 0 180)
			(layer "F.SilkS")
			(hide yes)
			(effects
				(font
					(size 1.27 1.27)
				)
			)
		)
		(property "Value" ""
			(at 0 0 180)
			(layer "F.Fab")
			(effects
				(font
					(size 1.27 1.27)
				)
			)
		)
		(duplicate_pad_numbers_are_jumpers no)
		(fp_line
			(start 0.7874 0.4064)
			(end -0.7874 0.4064)
			(stroke
				(width 0.1524)
				(type default)
			)
			(layer "F.SilkS")
		)
		(fp_line
			(start 0.7874 -0.4064)
			(end 0.7874 0.4064)
			(stroke
				(width 0.1524)
				(type default)
			)
			(layer "F.SilkS")
		)
		(fp_line
			(start -0.7874 0.4064)
			(end -0.7874 -0.4064)
			(stroke
				(width 0.1524)
				(type default)
			)
			(layer "F.SilkS")
		)
		(fp_line
			(start -0.7874 -0.4064)
			(end 0.7874 -0.4064)
			(stroke
				(width 0.1524)
				(type default)
			)
			(layer "F.SilkS")
		)
		(fp_line
			(start 0.67945 0.3048)
			(end 0.120396 0.3048)
			(stroke
				(width 0.1)
				(type default)
			)
			(layer "F.Fab")
		)
		(fp_line
			(start 0.67945 -0.3048)
			(end 0.67945 0.3048)
			(stroke
				(width 0.1)
				(type default)
			)
			(layer "F.Fab")
		)
		(fp_line
			(start 0.12065 -0.2794)
			(end 0.12065 -0.3048)
			(stroke
				(width 0.1)
				(type default)
			)
			(layer "F.Fab")
		)
		(fp_line
			(start 0.12065 -0.3048)
			(end 0.67945 -0.3048)
			(stroke
				(width 0.1)
				(type default)
			)
			(layer "F.Fab")
		)
		(fp_line
			(start 0.120396 0.3048)
			(end 0.120396 0.2794)
			(stroke
				(width 0.1)
				(type default)
			)
			(layer "F.Fab")
		)
		(fp_line
			(start 0.120396 0.2794)
			(end -0.12065 0.2794)
			(stroke
				(width 0.1)
				(type default)
			)
			(layer "F.Fab")
		)
		(fp_line
			(start -0.12065 0.3048)
			(end -0.67945 0.3048)
			(stroke
				(width 0.1)
				(type default)
			)
			(layer "F.Fab")
		)
		(fp_line
			(start -0.12065 0.2794)
			(end -0.12065 0.3048)
			(stroke
				(width 0.1)
				(type default)
			)
			(layer "F.Fab")
		)
		(fp_line
			(start -0.12065 -0.2794)
			(end 0.12065 -0.2794)
			(stroke
				(width 0.1)
				(type default)
			)
			(layer "F.Fab")
		)
		(fp_line
			(start -0.12065 -0.305054)
			(end -0.12065 -0.2794)
			(stroke
				(width 0.1)
				(type default)
			)
			(layer "F.Fab")
		)
		(fp_line
			(start -0.67945 0.3048)
			(end -0.67945 -0.305054)
			(stroke
				(width 0.1)
				(type default)
			)
			(layer "F.Fab")
		)
		(fp_line
			(start -0.67945 -0.305054)
			(end -0.12065 -0.305054)
			(stroke
				(width 0.1)
				(type default)
			)
			(layer "F.Fab")
		)
		(pad "1" smd circle
			(at -0.40005 0 180)
			(size 0 0)
			(layers "F.Cu" "F.Mask" "F.Paste")
			(net "P3V3_AUX")
		)
		(pad "2" smd circle
			(at 0.40005 0 180)
			(size 0 0)
			(layers "F.Cu" "F.Mask" "F.Paste")
			(net "SMB_FRU_3V3AUX_SDA")
		)
	)
	(footprint ""
		(layer "F.Cu")
		(at 401.110958 -321.002152 -90)
		(property "Reference" "R287"
			(at 0 0 270)
			(layer "F.SilkS")
			(hide yes)
			(effects
				(font
					(size 1.27 1.27)
				)
			)
		)
		(property "Value" ""
			(at 0 0 270)
			(layer "F.Fab")
			(effects
				(font
					(size 1.27 1.27)
				)
			)
		)
		(duplicate_pad_numbers_are_jumpers no)
		(fp_line
			(start -0.7874 0.4064)
			(end -0.7874 -0.4064)
			(stroke
				(width 0.1524)
				(type default)
			)
			(layer "F.SilkS")
		)
		(fp_line
			(start 0.7874 0.4064)
			(end -0.7874 0.4064)
			(stroke
				(width 0.1524)
				(type default)
			)
			(layer "F.SilkS")
		)
		(fp_line
			(start -0.7874 -0.4064)
			(end 0.7874 -0.4064)
			(stroke
				(width 0.1524)
				(type default)
			)
			(layer "F.SilkS")
		)
		(fp_line
			(start 0.7874 -0.4064)
			(end 0.7874 0.4064)
			(stroke
				(width 0.1524)
				(type default)
			)
			(layer "F.SilkS")
		)
		(fp_line
			(start -0.67945 0.3048)
			(end -0.67945 -0.305054)
			(stroke
				(width 0.1)
				(type default)
			)
			(layer "F.Fab")
		)
		(fp_line
			(start -0.12065 0.3048)
			(end -0.67945 0.3048)
			(stroke
				(width 0.1)
				(type default)
			)
			(layer "F.Fab")
		)
		(fp_line
			(start 0.120396 0.3048)
			(end 0.120396 0.2794)
			(stroke
				(width 0.1)
				(type default)
			)
			(layer "F.Fab")
		)
		(fp_line
			(start 0.67945 0.3048)
			(end 0.120396 0.3048)
			(stroke
				(width 0.1)
				(type default)
			)
			(layer "F.Fab")
		)
		(fp_line
			(start -0.12065 0.2794)
			(end -0.12065 0.3048)
			(stroke
				(width 0.1)
				(type default)
			)
			(layer "F.Fab")
		)
		(fp_line
			(start 0.120396 0.2794)
			(end -0.12065 0.2794)
			(stroke
				(width 0.1)
				(type default)
			)
			(layer "F.Fab")
		)
		(fp_line
			(start -0.12065 -0.2794)
			(end 0.12065 -0.2794)
			(stroke
				(width 0.1)
				(type default)
			)
			(layer "F.Fab")
		)
		(fp_line
			(start 0.12065 -0.2794)
			(end 0.12065 -0.3048)
			(stroke
				(width 0.1)
				(type default)
			)
			(layer "F.Fab")
		)
		(fp_line
			(start 0.12065 -0.3048)
			(end 0.67945 -0.3048)
			(stroke
				(width 0.1)
				(type default)
			)
			(layer "F.Fab")
		)
		(fp_line
			(start 0.67945 -0.3048)
			(end 0.67945 0.3048)
			(stroke
				(width 0.1)
				(type default)
			)
			(layer "F.Fab")
		)
		(fp_line
			(start -0.67945 -0.305054)
			(end -0.12065 -0.305054)
			(stroke
				(width 0.1)
				(type default)
			)
			(layer "F.Fab")
		)
		(fp_line
			(start -0.12065 -0.305054)
			(end -0.12065 -0.2794)
			(stroke
				(width 0.1)
				(type default)
			)
			(layer "F.Fab")
		)
		(pad "1" smd circle
			(at -0.40005 0 270)
			(size 0 0)
			(layers "F.Cu" "F.Mask" "F.Paste")
			(net "GND")
		)
		(pad "2" smd circle
			(at 0.40005 0 270)
			(size 0 0)
			(layers "F.Cu" "F.Mask" "F.Paste")
			(net "CPU0_PWR_GOOD")
		)
	)
	(footprint ""
		(layer "F.Cu")
		(at 304.419 -362.839 180)
		(property "Reference" "C8069"
			(at 0 0 180)
			(layer "F.SilkS")
			(hide yes)
			(effects
				(font
					(size 1.27 1.27)
				)
			)
		)
		(property "Value" ""
			(at 0 0 180)
			(layer "F.Fab")
			(effects
				(font
					(size 1.27 1.27)
				)
			)
		)
		(duplicate_pad_numbers_are_jumpers no)
		(fp_line
			(start 0.7874 0.4064)
			(end -0.7874 0.4064)
			(stroke
				(width 0.1524)
				(type default)
			)
			(layer "F.SilkS")
		)
		(fp_line
			(start 0.7874 -0.4064)
			(end 0.7874 0.4064)
			(stroke
				(width 0.1524)
				(type default)
			)
			(layer "F.SilkS")
		)
		(fp_line
			(start -0.7874 0.4064)
			(end -0.7874 -0.4064)
			(stroke
				(width 0.1524)
				(type default)
			)
			(layer "F.SilkS")
		)
		(fp_line
			(start -0.7874 -0.4064)
			(end 0.7874 -0.4064)
			(stroke
				(width 0.1524)
				(type default)
			)
			(layer "F.SilkS")
		)
		(fp_line
			(start 0.67945 0.3048)
			(end 0.120396 0.3048)
			(stroke
				(width 0.1)
				(type default)
			)
			(layer "F.Fab")
		)
		(fp_line
			(start 0.67945 -0.3048)
			(end 0.67945 0.3048)
			(stroke
				(width 0.1)
				(type default)
			)
			(layer "F.Fab")
		)
		(fp_line
			(start 0.12065 -0.2794)
			(end 0.12065 -0.3048)
			(stroke
				(width 0.1)
				(type default)
			)
			(layer "F.Fab")
		)
		(fp_line
			(start 0.12065 -0.3048)
			(end 0.67945 -0.3048)
			(stroke
				(width 0.1)
				(type default)
			)
			(layer "F.Fab")
		)
		(fp_line
			(start 0.120396 0.3048)
			(end 0.120396 0.2794)
			(stroke
				(width 0.1)
				(type default)
			)
			(layer "F.Fab")
		)
		(fp_line
			(start 0.120396 0.2794)
			(end -0.12065 0.2794)
			(stroke
				(width 0.1)
				(type default)
			)
			(layer "F.Fab")
		)
		(fp_line
			(start -0.12065 0.3048)
			(end -0.67945 0.3048)
			(stroke
				(width 0.1)
				(type default)
			)
			(layer "F.Fab")
		)
		(fp_line
			(start -0.12065 0.2794)
			(end -0.12065 0.3048)
			(stroke
				(width 0.1)
				(type default)
			)
			(layer "F.Fab")
		)
		(fp_line
			(start -0.12065 -0.2794)
			(end 0.12065 -0.2794)
			(stroke
				(width 0.1)
				(type default)
			)
			(layer "F.Fab")
		)
		(fp_line
			(start -0.12065 -0.305054)
			(end -0.12065 -0.2794)
			(stroke
				(width 0.1)
				(type default)
			)
			(layer "F.Fab")
		)
		(fp_line
			(start -0.67945 0.3048)
			(end -0.67945 -0.305054)
			(stroke
				(width 0.1)
				(type default)
			)
			(layer "F.Fab")
		)
		(fp_line
			(start -0.67945 -0.305054)
			(end -0.12065 -0.305054)
			(stroke
				(width 0.1)
				(type default)
			)
			(layer "F.Fab")
		)
		(pad "1" smd circle
			(at -0.40005 0 180)
			(size 0 0)
			(layers "F.Cu" "F.Mask" "F.Paste")
			(net "PVDDCR_CPU1_P0_EN_R")
		)
		(pad "2" smd circle
			(at 0.40005 0 180)
			(size 0 0)
			(layers "F.Cu" "F.Mask" "F.Paste")
			(net "GND")
		)
	)
)
